(kicad_pcb
	(version 20260206)
	(generator "pcbnew")
	(generator_version "10.0")
	(general
		(thickness 1.6)
		(legacy_teardrops no)
	)
	(paper "A4")
	(title_block
		(title "Wiwynn_Tioga_Pass_MB.brd")
		(comment 1 "Tioga Pass / footprint 190 of 4770 (U2D1), pads 3262-3369 of 3647")
	)
	(layers
		(0 "F.Cu" signal "TOP")
		(4 "In1.Cu" signal "L2GND")
		(6 "In2.Cu" signal "L3")
		(8 "In3.Cu" signal "L4GND")
		(10 "In4.Cu" signal "L5")
		(12 "In5.Cu" signal "L6GND")
		(14 "In6.Cu" signal "L7VCC")
		(16 "In7.Cu" signal "L8VCC")
		(18 "In8.Cu" signal "L9GND")
		(20 "In9.Cu" signal "L10")
		(22 "In10.Cu" signal "L11GND")
		(24 "In11.Cu" signal "L12")
		(26 "In12.Cu" signal "L13GND")
		(2 "B.Cu" signal "BOTTOM")
		(9 "F.Adhes" user "F.Adhesive")
		(11 "B.Adhes" user "B.Adhesive")
		(13 "F.Paste" user "Package Geometry/Pastemask Top")
		(15 "B.Paste" user "Package Geometry/Pastemask Bottom")
		(5 "F.SilkS" user "Ref Des/Silkscreen Top")
		(7 "B.SilkS" user "Ref Des/Silkscreen Bottom")
		(1 "F.Mask" user "Board Geometry/Soldermask Top")
		(3 "B.Mask" user "Board Geometry/Soldermask Bottom")
		(17 "Dwgs.User" user "User.Drawings")
		(19 "Cmts.User" user "User.Comments")
		(21 "Eco1.User" user "User.Eco1")
		(23 "Eco2.User" user "User.Eco2")
		(25 "Edge.Cuts" user "Board Geometry/Outline")
		(27 "Margin" user)
		(31 "F.CrtYd" user "Package Geometry/Place Bound Top")
		(29 "B.CrtYd" user "Package Geometry/Place Bound Bottom")
		(35 "F.Fab" user "Ref Des/Assembly Top")
		(33 "B.Fab" user "Ref Des/Assembly Bottom")
	)
	(footprint ""
		(layer "F.Cu")
		(at 104.99979 -76.550012 180)
		(property "Reference" "U2D1"
			(at 25.19299 30.484318 0)
			(unlocked yes)
			(layer "F.SilkS")
			(effects
				(font
					(size 0.7874 0.5842)
					(thickness 0.1524)
				)
			)
		)
		(property "Value" ""
			(at 0 0 180)
			(layer "F.Fab")
			(effects
				(font
					(size 1.27 1.27)
				)
			)
		)
		(duplicate_pad_numbers_are_jumpers no)
		(pad "L82" smd circle
			(at 33.816544 -21.950172)
			(size 0.4318 0.4318)
			(layers "F.Cu" "F.Mask" "F.Paste")
			(net "GND")
		)
		(pad "L84" smd circle
			(at 35.533584 -21.950172)
			(size 0.4318 0.4318)
			(layers "F.Cu" "F.Mask" "F.Paste")
			(net "M_G_DQ<11>")
		)
		(pad "L86" smd custom
			(at 37.250624 -21.950172 270)
			(size 0.10795 0.10795)
			(layers "F.Cu" "F.Mask" "F.Paste")
			(net "M_G_DQ<10>")
			(options
				(clearance outline)
				(anchor circle)
			)
			(primitives
				(gr_poly
					(pts
						(arc
							(start 0.2159 -0.0381)
							(mid 0 -0.254)
							(end -0.2159 -0.0381)
						)
						(arc
							(start -0.2159 0.0381)
							(mid 0 0.254)
							(end 0.2159 0.0381)
						)
					)
					(width 0)
					(fill yes)
				)
			)
		)
		(pad "M1" smd custom
			(at -37.250624 -19.655028 90)
			(size 0.10795 0.10795)
			(layers "F.Cu" "F.Mask" "F.Paste")
			(net "UPI_CPU1_CPU0_P0P0_DN<0>")
			(options
				(clearance outline)
				(anchor circle)
			)
			(primitives
				(gr_poly
					(pts
						(arc
							(start 0.2159 -0.0381)
							(mid 0 -0.254)
							(end -0.2159 -0.0381)
						)
						(arc
							(start -0.2159 0.0381)
							(mid 0 0.254)
							(end 0.2159 0.0381)
						)
					)
					(width 0)
					(fill yes)
				)
			)
		)
		(pad "M3" smd circle
			(at -35.533584 -19.655028)
			(size 0.4318 0.4318)
			(layers "F.Cu" "F.Mask" "F.Paste")
			(net "UPI_CPU1_CPU0_P1P1_DP<0>")
		)
		(pad "M5" smd circle
			(at -33.816544 -19.655028)
			(size 0.4318 0.4318)
			(layers "F.Cu" "F.Mask" "F.Paste")
			(net "UPI_CPU1_CPU0_P1P1_DP<2>")
		)
		(pad "M7" smd circle
			(at -32.099504 -19.655028)
			(size 0.4318 0.4318)
			(layers "F.Cu" "F.Mask" "F.Paste")
			(net "PVCCIO_CPU1")
		)
		(pad "M9" smd circle
			(at -30.382464 -19.655028)
			(size 0.4318 0.4318)
			(layers "F.Cu" "F.Mask" "F.Paste")
			(net "PVCCIO_CPU1")
		)
		(pad "M11" smd circle
			(at -28.665424 -19.655028)
			(size 0.4318 0.4318)
			(layers "F.Cu" "F.Mask" "F.Paste")
			(net "PVCCIO_CPU1")
		)
		(pad "M13" smd circle
			(at -26.948384 -19.655028)
			(size 0.4318 0.4318)
			(layers "F.Cu" "F.Mask" "F.Paste")
			(net "UPI_CPU0_CPU1_P1P1_DN<8>")
		)
		(pad "M15" smd circle
			(at -25.231598 -19.655028)
			(size 0.4318 0.4318)
			(layers "F.Cu" "F.Mask" "F.Paste")
			(net "GND")
		)
		(pad "M17" smd circle
			(at -23.514558 -19.655028)
			(size 0.4318 0.4318)
			(layers "F.Cu" "F.Mask" "F.Paste")
			(net "GND")
		)
		(pad "M19" smd circle
			(at -21.797518 -19.655028)
			(size 0.4318 0.4318)
			(layers "F.Cu" "F.Mask" "F.Paste")
			(net "GND")
		)
		(pad "M21" smd circle
			(at -20.080478 -19.655028)
			(size 0.4318 0.4318)
			(layers "F.Cu" "F.Mask" "F.Paste")
			(net "PVCCIO_CPU1")
		)
		(pad "M23" smd circle
			(at -18.363438 -19.655028)
			(size 0.4318 0.4318)
			(layers "F.Cu" "F.Mask" "F.Paste")
			(net "GND")
		)
		(pad "M25" smd circle
			(at -16.646398 -19.655028)
			(size 0.4318 0.4318)
			(layers "F.Cu" "F.Mask" "F.Paste")
			(net "GND")
		)
		(pad "M27" smd circle
			(at -14.929612 -19.655028)
			(size 0.4318 0.4318)
			(layers "F.Cu" "F.Mask" "F.Paste")
			(net "GND")
		)
		(pad "M29" smd circle
			(at -13.212572 -19.655028)
			(size 0.4318 0.4318)
			(layers "F.Cu" "F.Mask" "F.Paste")
			(net "GND")
		)
		(pad "M31" smd circle
			(at -11.495532 -19.655028)
			(size 0.4318 0.4318)
			(layers "F.Cu" "F.Mask" "F.Paste")
			(net "GND")
		)
		(pad "M33" smd circle
			(at -9.778492 -19.655028)
			(size 0.4318 0.4318)
			(layers "F.Cu" "F.Mask" "F.Paste")
			(net "GND")
		)
		(pad "M35" smd circle
			(at -8.061452 -19.655028)
			(size 0.4318 0.4318)
			(layers "F.Cu" "F.Mask" "F.Paste")
			(net "GND")
		)
		(pad "M37" smd circle
			(at -6.344412 -19.655028)
			(size 0.4318 0.4318)
			(layers "F.Cu" "F.Mask" "F.Paste")
			(net "GND")
		)
		(pad "M39" smd circle
			(at -4.627626 -19.655028)
			(size 0.4318 0.4318)
			(layers "F.Cu" "F.Mask" "F.Paste")
			(net "GND")
		)
		(pad "M41" smd circle
			(at -2.910586 -19.655028)
			(size 0.4318 0.4318)
			(layers "F.Cu" "F.Mask" "F.Paste")
			(net "GND")
		)
		(pad "M43" smd circle
			(at -1.193546 -19.655028)
			(size 0.4318 0.4318)
			(layers "F.Cu" "F.Mask" "F.Paste")
			(net "GND")
		)
		(pad "M45" smd circle
			(at 2.052066 -21.455126)
			(size 0.508 0.508)
			(layers "F.Cu" "F.Mask" "F.Paste")
			(net "M_H_CS_N<6>")
		)
		(pad "M47" smd circle
			(at 3.769106 -21.455126)
			(size 0.4318 0.4318)
			(layers "F.Cu" "F.Mask" "F.Paste")
			(net "M_H_C<2>")
		)
		(pad "M49" smd circle
			(at 5.485892 -21.455126)
			(size 0.4318 0.4318)
			(layers "F.Cu" "F.Mask" "F.Paste")
			(net "M_H_ODT<2>")
		)
		(pad "M51" smd circle
			(at 7.202932 -21.455126)
			(size 0.4318 0.4318)
			(layers "F.Cu" "F.Mask" "F.Paste")
			(net "M_H_MA<13>")
		)
		(pad "M53" smd circle
			(at 8.919972 -21.455126)
			(size 0.4318 0.4318)
			(layers "F.Cu" "F.Mask" "F.Paste")
			(net "M_H_CLK_DN<0>")
		)
		(pad "M55" smd circle
			(at 10.637012 -21.455126)
			(size 0.4318 0.4318)
			(layers "F.Cu" "F.Mask" "F.Paste")
			(net "M_H_MA<10>")
		)
		(pad "M57" smd circle
			(at 12.354052 -21.455126)
			(size 0.4318 0.4318)
			(layers "F.Cu" "F.Mask" "F.Paste")
			(net "M_H_CLK_DP<2>")
		)
		(pad "M59" smd circle
			(at 14.071092 -21.455126)
			(size 0.4318 0.4318)
			(layers "F.Cu" "F.Mask" "F.Paste")
			(net "M_H_MA<4>")
		)
		(pad "M61" smd circle
			(at 15.787878 -21.455126)
			(size 0.4318 0.4318)
			(layers "F.Cu" "F.Mask" "F.Paste")
			(net "M_H_BG<0>")
		)
		(pad "M63" smd circle
			(at 17.504918 -21.455126)
			(size 0.4318 0.4318)
			(layers "F.Cu" "F.Mask" "F.Paste")
			(net "TP_CPU1_RSVD_266")
		)
		(pad "M65" smd circle
			(at 19.221958 -21.455126)
			(size 0.4318 0.4318)
			(layers "F.Cu" "F.Mask" "F.Paste")
			(net "GND")
		)
		(pad "M67" smd circle
			(at 20.938998 -21.455126)
			(size 0.4318 0.4318)
			(layers "F.Cu" "F.Mask" "F.Paste")
			(net "M_H_ECC<7>")
		)
		(pad "M69" smd circle
			(at 22.656038 -21.455126)
			(size 0.4318 0.4318)
			(layers "F.Cu" "F.Mask" "F.Paste")
			(net "M_H_ECC<5>")
		)
		(pad "M71" smd circle
			(at 24.373078 -21.455126)
			(size 0.4318 0.4318)
			(layers "F.Cu" "F.Mask" "F.Paste")
			(net "GND")
		)
		(pad "M73" smd circle
			(at 26.090118 -21.455126)
			(size 0.4318 0.4318)
			(layers "F.Cu" "F.Mask" "F.Paste")
			(net "M_G_DQ<26>")
		)
		(pad "M75" smd circle
			(at 27.806904 -21.455126)
			(size 0.4318 0.4318)
			(layers "F.Cu" "F.Mask" "F.Paste")
			(net "M_G_DQS_DP<12>")
		)
		(pad "M77" smd circle
			(at 29.523944 -21.455126)
			(size 0.4318 0.4318)
			(layers "F.Cu" "F.Mask" "F.Paste")
			(net "M_G_DQ<28>")
		)
		(pad "M79" smd circle
			(at 31.240984 -21.455126)
			(size 0.4318 0.4318)
			(layers "F.Cu" "F.Mask" "F.Paste")
			(net "GND")
		)
		(pad "M81" smd circle
			(at 32.958024 -21.455126)
			(size 0.4318 0.4318)
			(layers "F.Cu" "F.Mask" "F.Paste")
			(net "M_G_DQ<19>")
		)
		(pad "M83" smd circle
			(at 34.675064 -21.455126)
			(size 0.4318 0.4318)
			(layers "F.Cu" "F.Mask" "F.Paste")
			(net "GND")
		)
		(pad "M85" smd circle
			(at 36.392104 -21.455126)
			(size 0.4318 0.4318)
			(layers "F.Cu" "F.Mask" "F.Paste")
			(net "GND")
		)
		(pad "N2" smd circle
			(at -36.392104 -19.159474)
			(size 0.4318 0.4318)
			(layers "F.Cu" "F.Mask" "F.Paste")
			(net "UPI_CPU1_CPU0_P0P0_DP<0>")
		)
		(pad "N4" smd circle
			(at -34.675064 -19.159474)
			(size 0.4318 0.4318)
			(layers "F.Cu" "F.Mask" "F.Paste")
			(net "GND")
		)
		(pad "N6" smd circle
			(at -32.958024 -19.159474)
			(size 0.4318 0.4318)
			(layers "F.Cu" "F.Mask" "F.Paste")
			(net "GND")
		)
		(pad "N8" smd circle
			(at -31.240984 -19.159474)
			(size 0.4318 0.4318)
			(layers "F.Cu" "F.Mask" "F.Paste")
			(net "GND")
		)
		(pad "N10" smd circle
			(at -29.523944 -19.159474)
			(size 0.4318 0.4318)
			(layers "F.Cu" "F.Mask" "F.Paste")
			(net "UPI_CPU0_CPU1_P1P1_DP<4>")
		)
		(pad "N12" smd circle
			(at -27.806904 -19.159474)
			(size 0.4318 0.4318)
			(layers "F.Cu" "F.Mask" "F.Paste")
			(net "UPI_CPU0_CPU1_P1P1_DP<7>")
		)
		(pad "N14" smd circle
			(at -26.090118 -19.159474)
			(size 0.4318 0.4318)
			(layers "F.Cu" "F.Mask" "F.Paste")
			(net "UPI_CPU0_CPU1_P1P1_DP<8>")
		)
		(pad "N16" smd circle
			(at -24.373078 -19.159474)
			(size 0.4318 0.4318)
			(layers "F.Cu" "F.Mask" "F.Paste")
			(net "UPI_CPU0_CPU1_P1P1_DN<11>")
		)
		(pad "N18" smd circle
			(at -22.656038 -19.159474)
			(size 0.4318 0.4318)
			(layers "F.Cu" "F.Mask" "F.Paste")
			(net "PVCCIO_CPU1")
		)
		(pad "N20" smd circle
			(at -20.938998 -19.159474)
			(size 0.4318 0.4318)
			(layers "F.Cu" "F.Mask" "F.Paste")
			(net "GND")
		)
		(pad "N22" smd circle
			(at -19.221958 -19.159474)
			(size 0.4318 0.4318)
			(layers "F.Cu" "F.Mask" "F.Paste")
			(net "GND")
		)
		(pad "N24" smd circle
			(at -17.504918 -19.159474)
			(size 0.4318 0.4318)
			(layers "F.Cu" "F.Mask" "F.Paste")
			(net "M_G_DQS_DN<7>")
		)
		(pad "N26" smd circle
			(at -15.787878 -19.159474)
			(size 0.4318 0.4318)
			(layers "F.Cu" "F.Mask" "F.Paste")
			(net "M_G_DQ<61>")
		)
		(pad "N28" smd circle
			(at -14.071092 -19.159474)
			(size 0.4318 0.4318)
			(layers "F.Cu" "F.Mask" "F.Paste")
			(net "M_G_DQ<51>")
		)
		(pad "N30" smd circle
			(at -12.354052 -19.159474)
			(size 0.4318 0.4318)
			(layers "F.Cu" "F.Mask" "F.Paste")
			(net "M_G_DQS_DP<6>")
		)
		(pad "N32" smd circle
			(at -10.637012 -19.159474)
			(size 0.4318 0.4318)
			(layers "F.Cu" "F.Mask" "F.Paste")
			(net "M_G_DQ<53>")
		)
		(pad "N34" smd circle
			(at -8.919972 -19.159474)
			(size 0.4318 0.4318)
			(layers "F.Cu" "F.Mask" "F.Paste")
			(net "M_G_DQ<43>")
		)
		(pad "N36" smd circle
			(at -7.202932 -19.159474)
			(size 0.4318 0.4318)
			(layers "F.Cu" "F.Mask" "F.Paste")
			(net "M_G_DQS_DP<5>")
		)
		(pad "N38" smd circle
			(at -5.485892 -19.159474)
			(size 0.4318 0.4318)
			(layers "F.Cu" "F.Mask" "F.Paste")
			(net "M_G_DQ<45>")
		)
		(pad "N40" smd circle
			(at -3.769106 -19.159474)
			(size 0.4318 0.4318)
			(layers "F.Cu" "F.Mask" "F.Paste")
			(net "M_H_DQ<35>")
		)
		(pad "N42" smd circle
			(at -2.052066 -19.159474)
			(size 0.4318 0.4318)
			(layers "F.Cu" "F.Mask" "F.Paste")
			(net "M_H_DQS_DN<4>")
		)
		(pad "N46" smd circle
			(at 2.910586 -20.959572)
			(size 0.4318 0.4318)
			(layers "F.Cu" "F.Mask" "F.Paste")
			(net "M_H_CS_N<2>")
		)
		(pad "N48" smd circle
			(at 4.627626 -20.959572)
			(size 0.4318 0.4318)
			(layers "F.Cu" "F.Mask" "F.Paste")
			(net "M_H_MA<17>")
		)
		(pad "N50" smd circle
			(at 6.344412 -20.959572)
			(size 0.4318 0.4318)
			(layers "F.Cu" "F.Mask" "F.Paste")
			(net "M_H_ODT<0>")
		)
		(pad "N52" smd circle
			(at 8.061452 -20.959572)
			(size 0.4318 0.4318)
			(layers "F.Cu" "F.Mask" "F.Paste")
			(net "M_H_MA<15>")
		)
		(pad "N54" smd circle
			(at 9.778492 -20.959572)
			(size 0.4318 0.4318)
			(layers "F.Cu" "F.Mask" "F.Paste")
			(net "M_H_CLK_DP<0>")
		)
		(pad "N56" smd circle
			(at 11.495532 -20.959572)
			(size 0.4318 0.4318)
			(layers "F.Cu" "F.Mask" "F.Paste")
			(net "M_H_CLK_DN<2>")
		)
		(pad "N58" smd circle
			(at 13.212572 -20.959572)
			(size 0.4318 0.4318)
			(layers "F.Cu" "F.Mask" "F.Paste")
			(net "M_H_MA<3>")
		)
		(pad "N60" smd circle
			(at 14.929612 -20.959572)
			(size 0.4318 0.4318)
			(layers "F.Cu" "F.Mask" "F.Paste")
			(net "M_H_BG<1>")
		)
		(pad "N62" smd circle
			(at 16.646398 -20.959572)
			(size 0.4318 0.4318)
			(layers "F.Cu" "F.Mask" "F.Paste")
			(net "M_H_CKE<0>")
		)
		(pad "N64" smd circle
			(at 18.363438 -20.959572)
			(size 0.4318 0.4318)
			(layers "F.Cu" "F.Mask" "F.Paste")
			(net "PVDDQ_GHJ")
		)
		(pad "N66" smd circle
			(at 20.080478 -20.959572)
			(size 0.4318 0.4318)
			(layers "F.Cu" "F.Mask" "F.Paste")
			(net "GND")
		)
		(pad "N68" smd circle
			(at 21.797518 -20.959572)
			(size 0.4318 0.4318)
			(layers "F.Cu" "F.Mask" "F.Paste")
			(net "M_H_DQS_DN<8>")
		)
		(pad "N70" smd circle
			(at 23.514558 -20.959572)
			(size 0.4318 0.4318)
			(layers "F.Cu" "F.Mask" "F.Paste")
			(net "GND")
		)
		(pad "N72" smd circle
			(at 25.231598 -20.959572)
			(size 0.4318 0.4318)
			(layers "F.Cu" "F.Mask" "F.Paste")
			(net "GND")
		)
		(pad "N74" smd circle
			(at 26.948384 -20.959572)
			(size 0.4318 0.4318)
			(layers "F.Cu" "F.Mask" "F.Paste")
			(net "GND")
		)
		(pad "N76" smd circle
			(at 28.665424 -20.959572)
			(size 0.4318 0.4318)
			(layers "F.Cu" "F.Mask" "F.Paste")
			(net "GND")
		)
		(pad "N78" smd circle
			(at 30.382464 -20.959572)
			(size 0.4318 0.4318)
			(layers "F.Cu" "F.Mask" "F.Paste")
			(net "GND")
		)
		(pad "N80" smd circle
			(at 32.099504 -20.959572)
			(size 0.4318 0.4318)
			(layers "F.Cu" "F.Mask" "F.Paste")
			(net "M_G_DQ<23>")
		)
		(pad "N82" smd circle
			(at 33.816544 -20.959572)
			(size 0.4318 0.4318)
			(layers "F.Cu" "F.Mask" "F.Paste")
			(net "M_G_DQ<18>")
		)
		(pad "N84" smd circle
			(at 35.533584 -20.959572)
			(size 0.4318 0.4318)
			(layers "F.Cu" "F.Mask" "F.Paste")
			(net "M_G_DQ<15>")
		)
		(pad "N86" smd custom
			(at 37.250624 -20.959572 270)
			(size 0.10795 0.10795)
			(layers "F.Cu" "F.Mask" "F.Paste")
			(net "M_G_DQ<14>")
			(options
				(clearance outline)
				(anchor circle)
			)
			(primitives
				(gr_poly
					(pts
						(arc
							(start 0.2159 -0.0381)
							(mid 0 -0.254)
							(end -0.2159 -0.0381)
						)
						(arc
							(start -0.2159 0.0381)
							(mid 0 0.254)
							(end 0.2159 0.0381)
						)
					)
					(width 0)
					(fill yes)
				)
			)
		)
		(pad "P1" smd custom
			(at -37.250624 -18.664428 90)
			(size 0.10795 0.10795)
			(layers "F.Cu" "F.Mask" "F.Paste")
			(net "UPI_CPU1_CPU0_P0P0_DP<1>")
			(options
				(clearance outline)
				(anchor circle)
			)
			(primitives
				(gr_poly
					(pts
						(arc
							(start 0.2159 -0.0381)
							(mid 0 -0.254)
							(end -0.2159 -0.0381)
						)
						(arc
							(start -0.2159 0.0381)
							(mid 0 0.254)
							(end 0.2159 0.0381)
						)
					)
					(width 0)
					(fill yes)
				)
			)
		)
		(pad "P3" smd circle
			(at -35.533584 -18.664428)
			(size 0.4318 0.4318)
			(layers "F.Cu" "F.Mask" "F.Paste")
			(net "UPI_CPU1_CPU0_P1P1_DN<0>")
		)
		(pad "P5" smd circle
			(at -33.816544 -18.664428)
			(size 0.4318 0.4318)
			(layers "F.Cu" "F.Mask" "F.Paste")
			(net "PVCCIO_CPU1")
		)
		(pad "P7" smd circle
			(at -32.099504 -18.664428)
			(size 0.4318 0.4318)
			(layers "F.Cu" "F.Mask" "F.Paste")
			(net "UPI_CPU0_CPU1_P1P1_DN<1>")
		)
		(pad "P9" smd circle
			(at -30.382464 -18.664428)
			(size 0.4318 0.4318)
			(layers "F.Cu" "F.Mask" "F.Paste")
			(net "UPI_CPU0_CPU1_P1P1_DN<4>")
		)
		(pad "P11" smd circle
			(at -28.665424 -18.664428)
			(size 0.4318 0.4318)
			(layers "F.Cu" "F.Mask" "F.Paste")
			(net "GND")
		)
		(pad "P13" smd circle
			(at -26.948384 -18.664428)
			(size 0.4318 0.4318)
			(layers "F.Cu" "F.Mask" "F.Paste")
			(net "UPI_CPU0_CPU1_P1P1_DP<9>")
		)
		(pad "P15" smd circle
			(at -25.231598 -18.664428)
			(size 0.4318 0.4318)
			(layers "F.Cu" "F.Mask" "F.Paste")
			(net "GND")
		)
		(pad "P17" smd circle
			(at -23.514558 -18.664428)
			(size 0.4318 0.4318)
			(layers "F.Cu" "F.Mask" "F.Paste")
			(net "UPI_CPU0_CPU1_P1P1_DP<11>")
		)
		(pad "P19" smd circle
			(at -21.797518 -18.664428)
			(size 0.4318 0.4318)
			(layers "F.Cu" "F.Mask" "F.Paste")
			(net "UPI_CPU0_CPU1_P1P1_DP<14>")
		)
		(pad "P21" smd circle
			(at -20.080478 -18.664428)
			(size 0.4318 0.4318)
			(layers "F.Cu" "F.Mask" "F.Paste")
			(net "UPI_CPU0_CPU1_P1P1_DN<16>")
		)
		(pad "P23" smd circle
			(at -18.363438 -18.664428)
			(size 0.4318 0.4318)
			(layers "F.Cu" "F.Mask" "F.Paste")
			(net "M_G_DQ<58>")
		)
		(pad "P25" smd circle
			(at -16.646398 -18.664428)
			(size 0.4318 0.4318)
			(layers "F.Cu" "F.Mask" "F.Paste")
			(net "M_G_DQ<57>")
		)
		(pad "P27" smd circle
			(at -14.929612 -18.664428)
			(size 0.4318 0.4318)
			(layers "F.Cu" "F.Mask" "F.Paste")
			(net "GND")
		)
		(pad "P29" smd circle
			(at -13.212572 -18.664428)
			(size 0.4318 0.4318)
			(layers "F.Cu" "F.Mask" "F.Paste")
			(net "M_G_DQ<55>")
		)
		(pad "P31" smd circle
			(at -11.495532 -18.664428)
			(size 0.4318 0.4318)
			(layers "F.Cu" "F.Mask" "F.Paste")
			(net "M_G_DQ<49>")
		)
		(pad "P33" smd circle
			(at -9.778492 -18.664428)
			(size 0.4318 0.4318)
			(layers "F.Cu" "F.Mask" "F.Paste")
			(net "GND")
		)
		(pad "P35" smd circle
			(at -8.061452 -18.664428)
			(size 0.4318 0.4318)
			(layers "F.Cu" "F.Mask" "F.Paste")
			(net "M_G_DQ<47>")
		)
		(pad "P37" smd circle
			(at -6.344412 -18.664428)
			(size 0.4318 0.4318)
			(layers "F.Cu" "F.Mask" "F.Paste")
			(net "M_G_DQ<41>")
		)
		(pad "P39" smd circle
			(at -4.627626 -18.664428)
			(size 0.4318 0.4318)
			(layers "F.Cu" "F.Mask" "F.Paste")
			(net "GND")
		)
	)
)
